# BASEBOARD_FAB2 (Tioga Pass) — schematic netlist excerpt (pin names and nets, part order shuffled) for the footprints in the layout excerpt that follows; sources: Cadence DE-HDL packaged netlist, KiCad conversion of Wiwynn_Tioga_Pass_MB.brd

U1L10  TTL3126  74CBTLV3126 IC  pkg QFNLF  page 189
  OE(3)  = BMC_JTAG_SEL_N_MUX
  A(3)  = JTAG_PLD_TDO_MUX
  B(3)  = JTAG_TDO
  OE(2)  = BMC_JTAG_SEL_N_MUX
  A(2)  = JTAG_PLD_TCK_MUX
  B(2)  = JTAG_TCK
  B(1)  = JTAG_TMS
  A(1)  = JTAG_PLD_TMS_MUX
  OE(1)  = BMC_JTAG_SEL_N_MUX
  B(0)  = JTAG_TDI
  A(0)  = JTAG_PLD_TDI_MUX
  OE(0)  = BMC_JTAG_SEL_N_MUX

(kicad_pcb
	(version 20260206)
	(generator "pcbnew")
	(generator_version "10.0")
	(general
		(thickness 1.6)
		(legacy_teardrops no)
	)
	(paper "A4")
	(title_block
		(title "Wiwynn_Tioga_Pass_MB.brd")
		(comment 1 "Tioga Pass / footprints 1120-1120 of 4770")
	)
	(layers
		(0 "F.Cu" signal "TOP")
		(4 "In1.Cu" signal "L2GND")
		(6 "In2.Cu" signal "L3")
		(8 "In3.Cu" signal "L4GND")
		(10 "In4.Cu" signal "L5")
		(12 "In5.Cu" signal "L6GND")
		(14 "In6.Cu" signal "L7VCC")
		(16 "In7.Cu" signal "L8VCC")
		(18 "In8.Cu" signal "L9GND")
		(20 "In9.Cu" signal "L10")
		(22 "In10.Cu" signal "L11GND")
		(24 "In11.Cu" signal "L12")
		(26 "In12.Cu" signal "L13GND")
		(2 "B.Cu" signal "BOTTOM")
		(9 "F.Adhes" user "F.Adhesive")
		(11 "B.Adhes" user "B.Adhesive")
		(13 "F.Paste" user "Package Geometry/Pastemask Top")
		(15 "B.Paste" user "Package Geometry/Pastemask Bottom")
		(5 "F.SilkS" user "Ref Des/Silkscreen Top")
		(7 "B.SilkS" user "Ref Des/Silkscreen Bottom")
		(1 "F.Mask" user "Board Geometry/Soldermask Top")
		(3 "B.Mask" user "Board Geometry/Soldermask Bottom")
		(17 "Dwgs.User" user "User.Drawings")
		(19 "Cmts.User" user "User.Comments")
		(21 "Eco1.User" user "User.Eco1")
		(23 "Eco2.User" user "User.Eco2")
		(25 "Edge.Cuts" user "Board Geometry/Outline")
		(27 "Margin" user)
		(31 "F.CrtYd" user "Package Geometry/Place Bound Top")
		(29 "B.CrtYd" user "Package Geometry/Place Bound Bottom")
		(35 "F.Fab" user "Ref Des/Assembly Top")
		(33 "B.Fab" user "Ref Des/Assembly Bottom")
	)
	(footprint ""
		(layer "F.Cu")
		(at 403.733 0.1524)
		(property "Reference" "U1L10"
			(at -1.743964 -3.834638 0)
			(unlocked yes)
			(layer "F.SilkS")
			(effects
				(font
					(size 3.048 1.524)
					(thickness 0.000001)
				)
				(justify left)
			)
		)
		(property "Value" ""
			(at 0 0 0)
			(layer "F.Fab")
			(effects
				(font
					(size 1.27 1.27)
				)
			)
		)
		(duplicate_pad_numbers_are_jumpers no)
		(fp_circle
			(center -1.17856 -2.466086)
			(end -1.05156 -2.466086)
			(stroke
				(width 0.254)
				(type default)
			)
			(fill no)
			(layer "F.SilkS")
		)
		(fp_rect
			(start -0.9144 0.9144)
			(end 0.9144 -0.9144)
			(stroke
				(width 0)
				(type default)
			)
			(fill yes)
			(layer "F.Paste")
		)
		(fp_rect
			(start -1.82499 1.82499)
			(end 1.82499 -1.82499)
			(stroke
				(width 0)
				(type default)
			)
			(fill no)
			(layer "F.CrtYd")
		)
		(fp_line
			(start -1.82499 -1.82499)
			(end 1.82499 -1.82499)
			(stroke
				(width 0.1)
				(type default)
			)
			(layer "F.Fab")
		)
		(fp_line
			(start -1.82499 1.82499)
			(end -1.82499 -1.82499)
			(stroke
				(width 0.1)
				(type default)
			)
			(layer "F.Fab")
		)
		(fp_line
			(start 1.82499 -1.82499)
			(end 1.82499 1.82499)
			(stroke
				(width 0.1)
				(type default)
			)
			(layer "F.Fab")
		)
		(fp_line
			(start 1.82499 1.82499)
			(end -1.82499 1.82499)
			(stroke
				(width 0.1)
				(type default)
			)
			(layer "F.Fab")
		)
		(fp_circle
			(center -1.17856 -2.466086)
			(end -1.05156 -2.466086)
			(stroke
				(width 0.254)
				(type default)
			)
			(fill no)
			(layer "F.Fab")
		)
		(pad "1" smd custom
			(at -0.750062 -1.549908)
			(size 0.0762 0.0762)
			(layers "F.Cu" "F.Mask" "F.Paste")
			(net "BMC_JTAG_SEL_N_MUX")
			(options
				(clearance outline)
				(anchor circle)
			)
			(primitives
				(gr_poly
					(pts
						(xy 0.1524 -0.381)
						(arc
							(start 0.1524 0.2286)
							(mid 0 0.381)
							(end -0.1524 0.2286)
						)
						(xy -0.1524 -0.381)
					)
					(width 0)
					(fill yes)
				)
			)
		)
		(pad "2" smd custom
			(at -1.549908 -0.999998)
			(size 0.0762 0.0762)
			(layers "F.Cu" "F.Mask" "F.Paste")
			(net "JTAG_PLD_TDO_MUX")
			(options
				(clearance outline)
				(anchor circle)
			)
			(primitives
				(gr_poly
					(pts
						(xy -0.381 -0.1524)
						(arc
							(start 0.2286 -0.1524)
							(mid 0.381 0)
							(end 0.2286 0.1524)
						)
						(xy -0.381 0.1524)
					)
					(width 0)
					(fill yes)
				)
			)
		)
		(pad "3" smd custom
			(at -1.549908 -0.500126)
			(size 0.0762 0.0762)
			(layers "F.Cu" "F.Mask" "F.Paste")
			(net "JTAG_TDO")
			(options
				(clearance outline)
				(anchor circle)
			)
			(primitives
				(gr_poly
					(pts
						(xy -0.381 -0.1524)
						(arc
							(start 0.2286 -0.1524)
							(mid 0.381 0)
							(end 0.2286 0.1524)
						)
						(xy -0.381 0.1524)
					)
					(width 0)
					(fill yes)
				)
			)
		)
		(pad "4" smd custom
			(at -1.549908 0)
			(size 0.0762 0.0762)
			(layers "F.Cu" "F.Mask" "F.Paste")
			(net "BMC_JTAG_SEL_N_MUX")
			(options
				(clearance outline)
				(anchor circle)
			)
			(primitives
				(gr_poly
					(pts
						(xy -0.381 -0.1524)
						(arc
							(start 0.2286 -0.1524)
							(mid 0.381 0)
							(end 0.2286 0.1524)
						)
						(xy -0.381 0.1524)
					)
					(width 0)
					(fill yes)
				)
			)
		)
		(pad "5" smd custom
			(at -1.549908 0.500126)
			(size 0.0762 0.0762)
			(layers "F.Cu" "F.Mask" "F.Paste")
			(net "JTAG_PLD_TCK_MUX")
			(options
				(clearance outline)
				(anchor circle)
			)
			(primitives
				(gr_poly
					(pts
						(xy -0.381 -0.1524)
						(arc
							(start 0.2286 -0.1524)
							(mid 0.381 0)
							(end 0.2286 0.1524)
						)
						(xy -0.381 0.1524)
					)
					(width 0)
					(fill yes)
				)
			)
		)
		(pad "6" smd custom
			(at -1.549908 0.999998)
			(size 0.0762 0.0762)
			(layers "F.Cu" "F.Mask" "F.Paste")
			(net "JTAG_TCK")
			(options
				(clearance outline)
				(anchor circle)
			)
			(primitives
				(gr_poly
					(pts
						(xy -0.381 -0.1524)
						(arc
							(start 0.2286 -0.1524)
							(mid 0.381 0)
							(end 0.2286 0.1524)
						)
						(xy -0.381 0.1524)
					)
					(width 0)
					(fill yes)
				)
			)
		)
		(pad "7" smd custom
			(at -0.750062 1.549908)
			(size 0.0762 0.0762)
			(layers "F.Cu" "F.Mask" "F.Paste")
			(net "GND")
			(options
				(clearance outline)
				(anchor circle)
			)
			(primitives
				(gr_poly
					(pts
						(xy -0.1524 0.381)
						(arc
							(start -0.1524 -0.2286)
							(mid 0 -0.381)
							(end 0.1524 -0.2286)
						)
						(xy 0.1524 0.381)
					)
					(width 0)
					(fill yes)
				)
			)
		)
		(pad "8" smd custom
			(at 0.769874 1.549908)
			(size 0.0762 0.0762)
			(layers "F.Cu" "F.Mask" "F.Paste")
			(net "JTAG_TMS")
			(options
				(clearance outline)
				(anchor circle)
			)
			(primitives
				(gr_poly
					(pts
						(xy -0.1524 0.381)
						(arc
							(start -0.1524 -0.2286)
							(mid 0 -0.381)
							(end 0.1524 -0.2286)
						)
						(xy 0.1524 0.381)
					)
					(width 0)
					(fill yes)
				)
			)
		)
		(pad "9" smd custom
			(at 1.549908 0.999998)
			(size 0.0762 0.0762)
			(layers "F.Cu" "F.Mask" "F.Paste")
			(net "JTAG_PLD_TMS_MUX")
			(options
				(clearance outline)
				(anchor circle)
			)
			(primitives
				(gr_poly
					(pts
						(xy 0.381 0.1524)
						(arc
							(start -0.2286 0.1524)
							(mid -0.381 0)
							(end -0.2286 -0.1524)
						)
						(xy 0.381 -0.1524)
					)
					(width 0)
					(fill yes)
				)
			)
		)
		(pad "10" smd custom
			(at 1.549908 0.500126)
			(size 0.0762 0.0762)
			(layers "F.Cu" "F.Mask" "F.Paste")
			(net "BMC_JTAG_SEL_N_MUX")
			(options
				(clearance outline)
				(anchor circle)
			)
			(primitives
				(gr_poly
					(pts
						(xy 0.381 0.1524)
						(arc
							(start -0.2286 0.1524)
							(mid -0.381 0)
							(end -0.2286 -0.1524)
						)
						(xy 0.381 -0.1524)
					)
					(width 0)
					(fill yes)
				)
			)
		)
		(pad "11" smd custom
			(at 1.549908 0)
			(size 0.0762 0.0762)
			(layers "F.Cu" "F.Mask" "F.Paste")
			(net "JTAG_TDI")
			(options
				(clearance outline)
				(anchor circle)
			)
			(primitives
				(gr_poly
					(pts
						(xy 0.381 0.1524)
						(arc
							(start -0.2286 0.1524)
							(mid -0.381 0)
							(end -0.2286 -0.1524)
						)
						(xy 0.381 -0.1524)
					)
					(width 0)
					(fill yes)
				)
			)
		)
		(pad "12" smd custom
			(at 1.549908 -0.500126)
			(size 0.0762 0.0762)
			(layers "F.Cu" "F.Mask" "F.Paste")
			(net "JTAG_PLD_TDI_MUX")
			(options
				(clearance outline)
				(anchor circle)
			)
			(primitives
				(gr_poly
					(pts
						(xy 0.381 0.1524)
						(arc
							(start -0.2286 0.1524)
							(mid -0.381 0)
							(end -0.2286 -0.1524)
						)
						(xy 0.381 -0.1524)
					)
					(width 0)
					(fill yes)
				)
			)
		)
		(pad "13" smd custom
			(at 1.549908 -0.999998)
			(size 0.0762 0.0762)
			(layers "F.Cu" "F.Mask" "F.Paste")
			(net "BMC_JTAG_SEL_N_MUX")
			(options
				(clearance outline)
				(anchor circle)
			)
			(primitives
				(gr_poly
					(pts
						(xy 0.381 0.1524)
						(arc
							(start -0.2286 0.1524)
							(mid -0.381 0)
							(end -0.2286 -0.1524)
						)
						(xy 0.381 -0.1524)
					)
					(width 0)
					(fill yes)
				)
			)
		)
		(pad "14" smd custom
			(at 0.750062 -1.549908)
			(size 0.0762 0.0762)
			(layers "F.Cu" "F.Mask" "F.Paste")
			(net "P3V3_STBY")
			(options
				(clearance outline)
				(anchor circle)
			)
			(primitives
				(gr_poly
					(pts
						(xy 0.1524 -0.381)
						(arc
							(start 0.1524 0.2286)
							(mid 0 0.381)
							(end -0.1524 0.2286)
						)
						(xy -0.1524 -0.381)
					)
					(width 0)
					(fill yes)
				)
			)
		)
		(pad "15" smd rect
			(at 0 0)
			(size 1.8288 1.8288)
			(layers "F.Cu" "F.Mask" "F.Paste")
			(net "GND")
		)
	)
)
